FILE_TYPE=LIBRARY_PARTS;
primitive 'ZENER_AC';
  pin
    'A':
      PIN_NUMBER='(A)';
      BIDIRECTIONAL='TRUE';
      INPUT_LOAD='(-0.01,0.01)';
      OUTPUT_LOAD='(1.0,-1.0)';
    'C':
      PIN_NUMBER='(C)';
      BIDIRECTIONAL='TRUE';
      INPUT_LOAD='(-0.01,0.01)';
      OUTPUT_LOAD='(1.0,-1.0)';
  end_pin;
  body
    PART_NAME='ZENER_AC';
    BODY_NAME='ZENER_AC';
    PHYS_DES_PREFIX='D';
    CLASS='DISCRETE';
  end_body;
end_primitive;

END.
